# T6G (Grand Teton) — schematic netlist excerpt (pin names and nets, part order shuffled) for the footprints in the layout excerpt that follows; sources: Cadence DE-HDL packaged netlist, KiCad conversion of 04192023_DAF0TMB3IC0_F0TG_MB_C_brd_V02_OCP.brd

PC516_2  Q_CAP  22UF 16V 20% X6S  pkg C0805  page 225 : A = SW_P12V_AUX_PVDD11_S3_P1_FLT ; B = GND
PC330_2  Q_CAP  22UF 16V 20% X6S  pkg C0805  page 215 : A = SW_P12V_AUX_PVDDCR_SOC_P1_FLT ; B = GND

Q107  MOSFET_NCH_DUAL  PJT138K IC  pkg SOT363XD  page 126
  S1  = GND
  G1  = GPU_PRSNT_N
  D2  = GPU_PRSNT_N_ISO
  S2  = GND
  G2  = GPU_PRSNT
  D1  = GPU_PRSNT

(kicad_pcb
	(version 20260206)
	(generator "pcbnew")
	(generator_version "10.0")
	(general
		(thickness 1.6)
		(legacy_teardrops no)
	)
	(paper "A4")
	(title_block
		(title "04192023_DAF0TMB3IC0_F0TG_MB_C_brd_V02_OCP.brd")
		(comment 1 "Grand Teton / footprints 5670-5672 of 8354")
	)
	(layers
		(0 "F.Cu" signal "TOP")
		(4 "In1.Cu" signal "GND")
		(6 "In2.Cu" signal "IN1")
		(8 "In3.Cu" signal "GND1")
		(10 "In4.Cu" signal "IN2")
		(12 "In5.Cu" signal "GND2")
		(14 "In6.Cu" signal "IN3")
		(16 "In7.Cu" signal "GND3")
		(18 "In8.Cu" signal "VCC")
		(20 "In9.Cu" signal "VCC1")
		(22 "In10.Cu" signal "GND4")
		(24 "In11.Cu" signal "IN4")
		(26 "In12.Cu" signal "GND5")
		(28 "In13.Cu" signal "IN5")
		(30 "In14.Cu" signal "GND6")
		(32 "In15.Cu" signal "IN6")
		(34 "In16.Cu" signal "GND7")
		(2 "B.Cu" signal "BOTTOM")
		(9 "F.Adhes" user "F.Adhesive")
		(11 "B.Adhes" user "B.Adhesive")
		(13 "F.Paste" user "Package Geometry/Pastemask Top")
		(15 "B.Paste" user "Package Geometry/Pastemask Bottom")
		(5 "F.SilkS" user "Ref Des/Silkscreen Top")
		(7 "B.SilkS" user "Ref Des/Silkscreen Bottom")
		(1 "F.Mask" user "Board Geometry/Soldermask Top")
		(3 "B.Mask" user "Board Geometry/Soldermask Bottom")
		(17 "Dwgs.User" user "User.Drawings")
		(19 "Cmts.User" user "User.Comments")
		(21 "Eco1.User" user "User.Eco1")
		(23 "Eco2.User" user "User.Eco2")
		(25 "Edge.Cuts" user "Board Geometry/Outline")
		(27 "Margin" user)
		(31 "F.CrtYd" user "Package Geometry/Place Bound Top")
		(29 "B.CrtYd" user "Package Geometry/Place Bound Bottom")
		(35 "F.Fab" user "Ref Des/Assembly Top")
		(33 "B.Fab" user "Ref Des/Assembly Bottom")
	)
	(footprint ""
		(layer "B.Cu")
		(at 48.65624 -429.114966)
		(property "Reference" "Q107"
			(at 1.138682 -2.10185 0)
			(unlocked yes)
			(layer "B.SilkS")
			(effects
				(font
					(size 0.7874 0.5842)
					(thickness 0.1524)
				)
				(justify left mirror)
			)
		)
		(property "Value" ""
			(at 0 0 0)
			(layer "B.Fab")
			(effects
				(font
					(size 1.27 1.27)
				)
				(justify mirror)
			)
		)
		(duplicate_pad_numbers_are_jumpers no)
		(fp_line
			(start -1.332738 -1.100074)
			(end -1.332738 1.100074)
			(stroke
				(width 0.1524)
				(type default)
			)
			(layer "B.SilkS")
		)
		(fp_line
			(start -1.332738 1.100074)
			(end 1.332738 1.100074)
			(stroke
				(width 0.1524)
				(type default)
			)
			(layer "B.SilkS")
		)
		(fp_line
			(start -0.4826 -1.100074)
			(end -1.332738 -1.100074)
			(stroke
				(width 0.1524)
				(type default)
			)
			(layer "B.SilkS")
		)
		(fp_line
			(start 0 -0.541274)
			(end -0.4826 -1.100074)
			(stroke
				(width 0.1524)
				(type default)
			)
			(layer "B.SilkS")
		)
		(fp_line
			(start 0.4826 -1.100074)
			(end 0 -0.541274)
			(stroke
				(width 0.1524)
				(type default)
			)
			(layer "B.SilkS")
		)
		(fp_line
			(start 1.332738 -1.100074)
			(end 0.4826 -1.100074)
			(stroke
				(width 0.1524)
				(type default)
			)
			(layer "B.SilkS")
		)
		(fp_line
			(start 1.332738 1.100074)
			(end 1.332738 -1.100074)
			(stroke
				(width 0.1524)
				(type default)
			)
			(layer "B.SilkS")
		)
		(fp_poly
			(pts
				(xy 1.668272 -0.896112) (xy 2.452878 -0.870458) (xy 2.159508 -1.508252)
			)
			(stroke
				(width 0)
				(type default)
			)
			(fill yes)
			(layer "B.SilkS")
		)
		(fp_line
			(start -0.674878 -1.100074)
			(end -0.674878 1.100074)
			(stroke
				(width 0.1)
				(type default)
			)
			(layer "B.Fab")
		)
		(fp_line
			(start -0.674878 1.100074)
			(end 0.674878 1.100074)
			(stroke
				(width 0.1)
				(type default)
			)
			(layer "B.Fab")
		)
		(fp_line
			(start 0.674878 -1.100074)
			(end -0.674878 -1.100074)
			(stroke
				(width 0.1)
				(type default)
			)
			(layer "B.Fab")
		)
		(fp_line
			(start 0.674878 1.100074)
			(end 0.674878 -1.100074)
			(stroke
				(width 0.1)
				(type default)
			)
			(layer "B.Fab")
		)
		(fp_poly
			(pts
				(xy 2.2352 -0.298958) (xy 2.2352 -1.001014) (xy 1.533144 -0.649986)
			)
			(stroke
				(width 0)
				(type default)
			)
			(fill yes)
			(layer "B.Fab")
		)
		(pad "1" smd rect
			(at 0.94996 -0.649986 90)
			(size 0.4318 0.508)
			(layers "B.Cu" "B.Mask" "B.Paste")
			(net "GND")
		)
		(pad "2" smd rect
			(at 0.94996 0 90)
			(size 0.4318 0.508)
			(layers "B.Cu" "B.Mask" "B.Paste")
			(net "GPU_PRSNT_N")
		)
		(pad "3" smd rect
			(at 0.94996 0.649986 90)
			(size 0.4318 0.508)
			(layers "B.Cu" "B.Mask" "B.Paste")
			(net "GPU_PRSNT_N_ISO")
		)
		(pad "4" smd rect
			(at -0.94996 0.649986 90)
			(size 0.4318 0.508)
			(layers "B.Cu" "B.Mask" "B.Paste")
			(net "GND")
		)
		(pad "5" smd rect
			(at -0.94996 0 90)
			(size 0.4318 0.508)
			(layers "B.Cu" "B.Mask" "B.Paste")
			(net "GPU_PRSNT")
		)
		(pad "6" smd rect
			(at -0.94996 -0.649986 90)
			(size 0.4318 0.508)
			(layers "B.Cu" "B.Mask" "B.Paste")
			(net "GPU_PRSNT")
		)
	)
	(footprint ""
		(layer "B.Cu")
		(at 122.888248 -165.079934 -90)
		(property "Reference" "PC330_2"
			(at 0 0 90)
			(layer "B.SilkS")
			(hide yes)
			(effects
				(font
					(size 1.27 1.27)
				)
				(justify mirror)
			)
		)
		(property "Value" ""
			(at 0 0 90)
			(layer "B.Fab")
			(effects
				(font
					(size 1.27 1.27)
				)
				(justify mirror)
			)
		)
		(duplicate_pad_numbers_are_jumpers no)
		(fp_line
			(start -1.524 0.762)
			(end 1.524 0.762)
			(stroke
				(width 0.1524)
				(type default)
			)
			(layer "B.SilkS")
		)
		(fp_line
			(start 1.524 0.762)
			(end 1.524 -0.762)
			(stroke
				(width 0.1524)
				(type default)
			)
			(layer "B.SilkS")
		)
		(fp_line
			(start -1.524 -0.762)
			(end -1.524 0.762)
			(stroke
				(width 0.1524)
				(type default)
			)
			(layer "B.SilkS")
		)
		(fp_line
			(start 1.524 -0.762)
			(end -1.524 -0.762)
			(stroke
				(width 0.1524)
				(type default)
			)
			(layer "B.SilkS")
		)
		(fp_line
			(start -1.1049 0.724916)
			(end -1.1049 -0.724916)
			(stroke
				(width 0.1)
				(type default)
			)
			(layer "B.Fab")
		)
		(fp_line
			(start 1.1049 0.724916)
			(end -1.1049 0.724916)
			(stroke
				(width 0.1)
				(type default)
			)
			(layer "B.Fab")
		)
		(fp_line
			(start -1.1049 -0.724916)
			(end 1.1049 -0.724916)
			(stroke
				(width 0.1)
				(type default)
			)
			(layer "B.Fab")
		)
		(fp_line
			(start 1.1049 -0.724916)
			(end 1.1049 0.724916)
			(stroke
				(width 0.1)
				(type default)
			)
			(layer "B.Fab")
		)
		(pad "1" smd rect
			(at 0.889 0 270)
			(size 1.016 1.27)
			(layers "B.Cu" "B.Mask" "B.Paste")
			(net "SW_P12V_AUX_PVDDCR_SOC_P1_FLT")
		)
		(pad "2" smd rect
			(at -0.889 0 270)
			(size 1.016 1.27)
			(layers "B.Cu" "B.Mask" "B.Paste")
			(net "GND")
		)
	)
	(footprint ""
		(layer "B.Cu")
		(at 192.27292 -351.23882 90)
		(property "Reference" "PC516_2"
			(at 0 0 90)
			(layer "B.SilkS")
			(hide yes)
			(effects
				(font
					(size 1.27 1.27)
				)
				(justify mirror)
			)
		)
		(property "Value" ""
			(at 0 0 90)
			(layer "B.Fab")
			(effects
				(font
					(size 1.27 1.27)
				)
				(justify mirror)
			)
		)
		(duplicate_pad_numbers_are_jumpers no)
		(fp_line
			(start 1.524 -0.762)
			(end -1.524 -0.762)
			(stroke
				(width 0.1524)
				(type default)
			)
			(layer "B.SilkS")
		)
		(fp_line
			(start -1.524 -0.762)
			(end -1.524 0.762)
			(stroke
				(width 0.1524)
				(type default)
			)
			(layer "B.SilkS")
		)
		(fp_line
			(start 1.524 0.762)
			(end 1.524 -0.762)
			(stroke
				(width 0.1524)
				(type default)
			)
			(layer "B.SilkS")
		)
		(fp_line
			(start -1.524 0.762)
			(end 1.524 0.762)
			(stroke
				(width 0.1524)
				(type default)
			)
			(layer "B.SilkS")
		)
		(fp_line
			(start 1.1049 -0.724916)
			(end 1.1049 0.724916)
			(stroke
				(width 0.1)
				(type default)
			)
			(layer "B.Fab")
		)
		(fp_line
			(start -1.1049 -0.724916)
			(end 1.1049 -0.724916)
			(stroke
				(width 0.1)
				(type default)
			)
			(layer "B.Fab")
		)
		(fp_line
			(start 1.1049 0.724916)
			(end -1.1049 0.724916)
			(stroke
				(width 0.1)
				(type default)
			)
			(layer "B.Fab")
		)
		(fp_line
			(start -1.1049 0.724916)
			(end -1.1049 -0.724916)
			(stroke
				(width 0.1)
				(type default)
			)
			(layer "B.Fab")
		)
		(pad "1" smd rect
			(at 0.889 0 90)
			(size 1.016 1.27)
			(layers "B.Cu" "B.Mask" "B.Paste")
			(net "SW_P12V_AUX_PVDD11_S3_P1_FLT")
		)
		(pad "2" smd rect
			(at -0.889 0 90)
			(size 1.016 1.27)
			(layers "B.Cu" "B.Mask" "B.Paste")
			(net "GND")
		)
	)
)
